#ISCELL
  mstr_symbols bom_note *
  *
#ISCELL
  mstr_symbols intel_corp_bpage *
  *
#ISCELL
  mstr_standard offpage *
  page77_i1
#ISCELL
  mstr_standard tap *
  page77_i10
#ISCELL
  mstr_standard tap *
  page77_i100
#ISCELL
  mstr_standard tap *
  page77_i101
#ISCELL
  mstr_standard tap *
  page77_i102
#ISCELL
  mstr_standard tap *
  page77_i103
#ISCELL
  mstr_standard tap *
  page77_i104
#ISCELL
  mstr_standard tap *
  page77_i105
#ISCELL
  mstr_standard tap *
  page77_i106
#ISCELL
  mstr_standard tap *
  page77_i107
#ISCELL
  mstr_standard tap *
  page77_i108
#ISCELL
  mstr_standard tap *
  page77_i109
#ISCELL
  mstr_standard tap *
  page77_i11
#ISCELL
  mstr_standard tap *
  page77_i110
#CELL
  mstr_sconn sconn288_h44441004 *
  page77_i111
#ISCELL
  mstr_standard tap *
  page77_i112
#ISCELL
  mstr_standard tap *
  page77_i113
#ISCELL
  mstr_standard tap *
  page77_i114
#ISCELL
  mstr_standard tap *
  page77_i115
#ISCELL
  mstr_standard tap *
  page77_i116
#ISCELL
  mstr_standard tap *
  page77_i117
#ISCELL
  mstr_standard tap *
  page77_i118
#ISCELL
  mstr_standard tap *
  page77_i119
#ISCELL
  mstr_standard tap *
  page77_i12
#ISCELL
  mstr_standard tap *
  page77_i120
#ISCELL
  mstr_standard tap *
  page77_i121
#ISCELL
  mstr_standard tap *
  page77_i122
#ISCELL
  mstr_standard tap *
  page77_i123
#ISCELL
  mstr_standard tap *
  page77_i124
#ISCELL
  mstr_standard tap *
  page77_i125
#ISCELL
  mstr_standard tap *
  page77_i126
#ISCELL
  mstr_standard tap *
  page77_i127
#ISCELL
  mstr_standard tap *
  page77_i128
#ISCELL
  mstr_standard tap *
  page77_i129
#ISCELL
  mstr_standard tap *
  page77_i13
#ISCELL
  mstr_standard tap *
  page77_i130
#ISCELL
  mstr_standard offpage *
  page77_i131
#ISCELL
  mstr_standard offpage *
  page77_i132
#ISCELL
  mstr_standard tap *
  page77_i133
#ISCELL
  mstr_standard tap *
  page77_i134
#ISCELL
  mstr_standard tap *
  page77_i135
#ISCELL
  mstr_standard offpage *
  page77_i136
#ISCELL
  mstr_standard offpage *
  page77_i137
#ISCELL
  mstr_standard tap *
  page77_i138
#ISCELL
  mstr_standard tap *
  page77_i139
#ISCELL
  mstr_standard tap *
  page77_i14
#ISCELL
  mstr_standard tap *
  page77_i140
#ISCELL
  mstr_standard tap *
  page77_i141
#ISCELL
  mstr_standard tap *
  page77_i142
#ISCELL
  mstr_standard tap *
  page77_i143
#ISCELL
  mstr_standard tap *
  page77_i144
#ISCELL
  mstr_standard tap *
  page77_i145
#ISCELL
  mstr_standard offpage *
  page77_i147
#ISCELL
  mstr_standard offpage *
  page77_i148
#ISCELL
  mstr_standard offpage *
  page77_i149
#ISCELL
  mstr_standard tap *
  page77_i15
#ISCELL
  mstr_standard offpage *
  page77_i150
#ISCELL
  mstr_standard tap *
  page77_i152
#ISCELL
  mstr_standard tap *
  page77_i153
#ISCELL
  mstr_standard offpage *
  page77_i154
#ISCELL
  mstr_standard offpage *
  page77_i155
#ISCELL
  mstr_standard tap *
  page77_i156
#ISCELL
  mstr_standard tap *
  page77_i157
#ISCELL
  mstr_standard tap *
  page77_i158
#ISCELL
  mstr_standard tap *
  page77_i159
#ISCELL
  mstr_symbols pvddq_ghj *
  page77_i16
#ISCELL
  mstr_standard tap *
  page77_i160
#ISCELL
  mstr_standard tap *
  page77_i161
#ISCELL
  mstr_standard tap *
  page77_i162
#ISCELL
  mstr_standard offpage *
  page77_i163
#ISCELL
  mstr_standard offpage *
  page77_i164
#ISCELL
  mstr_standard tap *
  page77_i165
#ISCELL
  mstr_standard tap *
  page77_i166
#ISCELL
  mstr_standard offpage *
  page77_i167
#ISCELL
  mstr_standard tap *
  page77_i168
#ISCELL
  mstr_symbols pvtt_ghj *
  page77_i17
#CELL
  mstr_sconn sconn288_h44441004 *
  page77_i171
#ISCELL
  mstr_symbols gnd *
  page77_i172
#ISCELL
  mstr_standard offpage *
  page77_i173
#ISCELL
  mstr_standard offpage *
  page77_i174
#ISCELL
  mstr_standard offpage *
  page77_i175
#ISCELL
  mstr_symbols gnd *
  page77_i177
#ISCELL
  mstr_standard offpage *
  page77_i178
#ISCELL
  mstr_standard offpage *
  page77_i179
#ISCELL
  mstr_symbols gnd *
  page77_i180
#CELL
  dev_discrete cap_a *
  page77_i181
#ISCELL
  mstr_symbols pvpp_ghj *
  page77_i182
#ISCELL
  mstr_symbols pvpp_ghj *
  page77_i183
#ISCELL
  mstr_standard offpage *
  page77_i184
#ISCELL
  mstr_standard tap *
  page77_i19
#ISCELL
  mstr_symbols p12v_nvdimm_ghj *
  page77_i197
#ISCELL
  mstr_standard offpage *
  page77_i2
#ISCELL
  mstr_standard tap *
  page77_i20
#ISCELL
  mstr_standard tap *
  page77_i21
#ISCELL
  mstr_standard tap *
  page77_i22
#ISCELL
  mstr_standard tap *
  page77_i23
#ISCELL
  mstr_standard tap *
  page77_i24
#ISCELL
  mstr_standard tap *
  page77_i25
#ISCELL
  mstr_standard tap *
  page77_i26
#ISCELL
  mstr_standard tap *
  page77_i27
#ISCELL
  mstr_standard tap *
  page77_i28
#ISCELL
  mstr_standard tap *
  page77_i29
#ISCELL
  mstr_standard tap *
  page77_i3
#ISCELL
  mstr_standard tap *
  page77_i30
#ISCELL
  mstr_standard tap *
  page77_i31
#ISCELL
  mstr_standard tap *
  page77_i32
#ISCELL
  mstr_standard tap *
  page77_i33
#ISCELL
  mstr_standard tap *
  page77_i34
#ISCELL
  mstr_standard tap *
  page77_i35
#ISCELL
  mstr_standard tap *
  page77_i36
#ISCELL
  mstr_standard tap *
  page77_i37
#ISCELL
  mstr_standard tap *
  page77_i38
#ISCELL
  mstr_standard tap *
  page77_i39
#ISCELL
  mstr_standard tap *
  page77_i4
#ISCELL
  mstr_standard tap *
  page77_i40
#ISCELL
  mstr_standard tap *
  page77_i41
#CELL
  mstr_sconn sconn288_h44441004 *
  page77_i43
#ISCELL
  mstr_symbols gnd *
  page77_i44
#ISCELL
  mstr_standard offpage *
  page77_i45
#ISCELL
  mstr_standard tap *
  page77_i46
#ISCELL
  mstr_standard tap *
  page77_i47
#ISCELL
  mstr_standard tap *
  page77_i48
#ISCELL
  mstr_standard tap *
  page77_i49
#ISCELL
  mstr_standard tap *
  page77_i5
#ISCELL
  mstr_standard tap *
  page77_i50
#ISCELL
  mstr_standard tap *
  page77_i51
#ISCELL
  mstr_standard tap *
  page77_i52
#ISCELL
  mstr_standard tap *
  page77_i53
#ISCELL
  mstr_standard tap *
  page77_i54
#ISCELL
  mstr_standard tap *
  page77_i55
#ISCELL
  mstr_standard tap *
  page77_i56
#ISCELL
  mstr_standard tap *
  page77_i57
#ISCELL
  mstr_standard tap *
  page77_i58
#ISCELL
  mstr_standard tap *
  page77_i59
#ISCELL
  mstr_standard tap *
  page77_i6
#ISCELL
  mstr_standard tap *
  page77_i60
#ISCELL
  mstr_standard tap *
  page77_i61
#ISCELL
  mstr_standard tap *
  page77_i62
#ISCELL
  mstr_standard tap *
  page77_i63
#ISCELL
  mstr_standard tap *
  page77_i64
#ISCELL
  mstr_standard tap *
  page77_i65
#CELL
  mstr_sconn sconn288_h44441004 *
  page77_i66
#ISCELL
  mstr_standard tap *
  page77_i67
#ISCELL
  mstr_standard tap *
  page77_i68
#ISCELL
  mstr_standard tap *
  page77_i69
#ISCELL
  mstr_standard tap *
  page77_i7
#ISCELL
  mstr_standard tap *
  page77_i70
#ISCELL
  mstr_standard tap *
  page77_i71
#ISCELL
  mstr_standard tap *
  page77_i72
#ISCELL
  mstr_standard tap *
  page77_i73
#ISCELL
  mstr_standard tap *
  page77_i74
#ISCELL
  mstr_standard tap *
  page77_i75
#ISCELL
  mstr_standard tap *
  page77_i76
#ISCELL
  mstr_standard tap *
  page77_i77
#ISCELL
  mstr_standard tap *
  page77_i78
#ISCELL
  mstr_standard tap *
  page77_i79
#ISCELL
  mstr_standard tap *
  page77_i8
#ISCELL
  mstr_standard tap *
  page77_i80
#ISCELL
  mstr_standard tap *
  page77_i81
#ISCELL
  mstr_standard tap *
  page77_i82
#ISCELL
  mstr_standard tap *
  page77_i83
#ISCELL
  mstr_standard tap *
  page77_i84
#ISCELL
  mstr_standard tap *
  page77_i85
#ISCELL
  mstr_standard tap *
  page77_i86
#ISCELL
  mstr_standard tap *
  page77_i87
#ISCELL
  mstr_standard tap *
  page77_i88
#ISCELL
  mstr_standard tap *
  page77_i89
#ISCELL
  mstr_standard tap *
  page77_i9
#ISCELL
  mstr_standard tap *
  page77_i90
#ISCELL
  mstr_standard tap *
  page77_i91
#ISCELL
  mstr_standard tap *
  page77_i92
#ISCELL
  mstr_standard tap *
  page77_i93
#ISCELL
  mstr_standard tap *
  page77_i94
#ISCELL
  mstr_standard tap *
  page77_i95
#ISCELL
  mstr_standard tap *
  page77_i96
#ISCELL
  mstr_standard tap *
  page77_i97
#ISCELL
  mstr_standard tap *
  page77_i98
#ISCELL
  mstr_standard tap *
  page77_i99
